(kicad_pcb
	(version 20260206)
	(generator "pcbnew")
	(generator_version "10.0")
	(general
		(thickness 1.6)
		(legacy_teardrops no)
	)
	(paper "A4")
	(title_block
		(title "01162023_DA0F0TEBIF0_F0T_Expander_BD_F_brd_V02_OCP.brd")
		(comment 1 "Grand Teton / footprints 3470-3475 of 9728")
	)
	(layers
		(0 "F.Cu" signal "TOP")
		(4 "In1.Cu" signal "GND")
		(6 "In2.Cu" signal "VCC")
		(8 "In3.Cu" signal "VCC1")
		(10 "In4.Cu" signal "GND1")
		(12 "In5.Cu" signal "IN1")
		(14 "In6.Cu" signal "GND2")
		(16 "In7.Cu" signal "IN2")
		(18 "In8.Cu" signal "GND3")
		(20 "In9.Cu" signal "IN3")
		(22 "In10.Cu" signal "GND4")
		(24 "In11.Cu" signal "IN4")
		(26 "In12.Cu" signal "GND5")
		(28 "In13.Cu" signal "IN5")
		(30 "In14.Cu" signal "GND6")
		(32 "In15.Cu" signal "IN6")
		(34 "In16.Cu" signal "GND7")
		(2 "B.Cu" signal "BOTTOM")
		(9 "F.Adhes" user "F.Adhesive")
		(11 "B.Adhes" user "B.Adhesive")
		(13 "F.Paste" user "Package Geometry/Pastemask Top")
		(15 "B.Paste" user "Package Geometry/Pastemask Bottom")
		(5 "F.SilkS" user "Ref Des/Silkscreen Top")
		(7 "B.SilkS" user "Ref Des/Silkscreen Bottom")
		(1 "F.Mask" user "Board Geometry/Soldermask Top")
		(3 "B.Mask" user "Board Geometry/Soldermask Bottom")
		(17 "Dwgs.User" user "User.Drawings")
		(19 "Cmts.User" user "User.Comments")
		(21 "Eco1.User" user "User.Eco1")
		(23 "Eco2.User" user "User.Eco2")
		(25 "Edge.Cuts" user "Board Geometry/Outline")
		(27 "Margin" user)
		(31 "F.CrtYd" user "Package Geometry/Place Bound Top")
		(29 "B.CrtYd" user "Package Geometry/Place Bound Bottom")
		(35 "F.Fab" user "Ref Des/Assembly Top")
		(33 "B.Fab" user "Ref Des/Assembly Bottom")
	)
	(footprint ""
		(layer "F.Cu")
		(at 129.690114 -259.147564 180)
		(property "Reference" "R832"
			(at 0 0 180)
			(layer "F.SilkS")
			(hide yes)
			(effects
				(font
					(size 1.27 1.27)
				)
			)
		)
		(property "Value" ""
			(at 0 0 180)
			(layer "F.Fab")
			(effects
				(font
					(size 1.27 1.27)
				)
			)
		)
		(duplicate_pad_numbers_are_jumpers no)
		(fp_line
			(start 0.7874 0.4064)
			(end -0.7874 0.4064)
			(stroke
				(width 0.1524)
				(type default)
			)
			(layer "F.SilkS")
		)
		(fp_line
			(start 0.7874 -0.4064)
			(end 0.7874 0.4064)
			(stroke
				(width 0.1524)
				(type default)
			)
			(layer "F.SilkS")
		)
		(fp_line
			(start -0.7874 0.4064)
			(end -0.7874 -0.4064)
			(stroke
				(width 0.1524)
				(type default)
			)
			(layer "F.SilkS")
		)
		(fp_line
			(start -0.7874 -0.4064)
			(end 0.7874 -0.4064)
			(stroke
				(width 0.1524)
				(type default)
			)
			(layer "F.SilkS")
		)
		(fp_line
			(start 0.67945 0.3048)
			(end 0.120396 0.3048)
			(stroke
				(width 0.1)
				(type default)
			)
			(layer "F.Fab")
		)
		(fp_line
			(start 0.67945 -0.3048)
			(end 0.67945 0.3048)
			(stroke
				(width 0.1)
				(type default)
			)
			(layer "F.Fab")
		)
		(fp_line
			(start 0.12065 -0.2794)
			(end 0.12065 -0.3048)
			(stroke
				(width 0.1)
				(type default)
			)
			(layer "F.Fab")
		)
		(fp_line
			(start 0.12065 -0.3048)
			(end 0.67945 -0.3048)
			(stroke
				(width 0.1)
				(type default)
			)
			(layer "F.Fab")
		)
		(fp_line
			(start 0.120396 0.3048)
			(end 0.120396 0.2794)
			(stroke
				(width 0.1)
				(type default)
			)
			(layer "F.Fab")
		)
		(fp_line
			(start 0.120396 0.2794)
			(end -0.12065 0.2794)
			(stroke
				(width 0.1)
				(type default)
			)
			(layer "F.Fab")
		)
		(fp_line
			(start -0.12065 0.3048)
			(end -0.67945 0.3048)
			(stroke
				(width 0.1)
				(type default)
			)
			(layer "F.Fab")
		)
		(fp_line
			(start -0.12065 0.2794)
			(end -0.12065 0.3048)
			(stroke
				(width 0.1)
				(type default)
			)
			(layer "F.Fab")
		)
		(fp_line
			(start -0.12065 -0.2794)
			(end 0.12065 -0.2794)
			(stroke
				(width 0.1)
				(type default)
			)
			(layer "F.Fab")
		)
		(fp_line
			(start -0.12065 -0.305054)
			(end -0.12065 -0.2794)
			(stroke
				(width 0.1)
				(type default)
			)
			(layer "F.Fab")
		)
		(fp_line
			(start -0.67945 0.3048)
			(end -0.67945 -0.305054)
			(stroke
				(width 0.1)
				(type default)
			)
			(layer "F.Fab")
		)
		(fp_line
			(start -0.67945 -0.305054)
			(end -0.12065 -0.305054)
			(stroke
				(width 0.1)
				(type default)
			)
			(layer "F.Fab")
		)
		(pad "1" smd circle
			(at -0.40005 0 180)
			(size 0 0)
			(layers "F.Cu" "F.Mask" "F.Paste")
			(net "PWRGD_P0V8_PEX1_R")
		)
		(pad "2" smd circle
			(at 0.40005 0 180)
			(size 0 0)
			(layers "F.Cu" "F.Mask" "F.Paste")
			(net "P0V8_PEX1_BVRRDY")
		)
	)
	(footprint ""
		(layer "F.Cu")
		(at 424.814492 -343.952322 90)
		(property "Reference" "C2453"
			(at 0 0 90)
			(layer "F.SilkS")
			(hide yes)
			(effects
				(font
					(size 1.27 1.27)
				)
			)
		)
		(property "Value" ""
			(at 0 0 90)
			(layer "F.Fab")
			(effects
				(font
					(size 1.27 1.27)
				)
			)
		)
		(duplicate_pad_numbers_are_jumpers no)
		(fp_line
			(start 0.299974 -0.150114)
			(end 0.299974 0.150114)
			(stroke
				(width 0.1)
				(type default)
			)
			(layer "F.Fab")
		)
		(fp_line
			(start -0.299974 -0.150114)
			(end 0.299974 -0.150114)
			(stroke
				(width 0.1)
				(type default)
			)
			(layer "F.Fab")
		)
		(fp_line
			(start 0.299974 0.150114)
			(end -0.299974 0.150114)
			(stroke
				(width 0.1)
				(type default)
			)
			(layer "F.Fab")
		)
		(fp_line
			(start -0.299974 0.150114)
			(end -0.299974 -0.150114)
			(stroke
				(width 0.1)
				(type default)
			)
			(layer "F.Fab")
		)
		(pad "1" smd rect
			(at -0.2667 0 90)
			(size 0.3048 0.381)
			(layers "F.Cu" "F.Mask" "F.Paste")
			(net "P5E_PEX3_STN4_TX_DP<72>")
		)
		(pad "2" smd rect
			(at 0.2667 0 90)
			(size 0.3048 0.381)
			(layers "F.Cu" "F.Mask" "F.Paste")
			(net "P5E_PEX3_STN4_TX_C_DP<72>")
		)
	)
	(footprint ""
		(layer "F.Cu")
		(at 353.594162 -35.264852)
		(property "Reference" "R5703"
			(at 0 0 0)
			(layer "F.SilkS")
			(hide yes)
			(effects
				(font
					(size 1.27 1.27)
				)
			)
		)
		(property "Value" ""
			(at 0 0 0)
			(layer "F.Fab")
			(effects
				(font
					(size 1.27 1.27)
				)
			)
		)
		(duplicate_pad_numbers_are_jumpers no)
		(fp_line
			(start -0.7874 -0.4064)
			(end 0.7874 -0.4064)
			(stroke
				(width 0.1524)
				(type default)
			)
			(layer "F.SilkS")
		)
		(fp_line
			(start -0.7874 0.4064)
			(end -0.7874 -0.4064)
			(stroke
				(width 0.1524)
				(type default)
			)
			(layer "F.SilkS")
		)
		(fp_line
			(start 0.7874 -0.4064)
			(end 0.7874 0.4064)
			(stroke
				(width 0.1524)
				(type default)
			)
			(layer "F.SilkS")
		)
		(fp_line
			(start 0.7874 0.4064)
			(end -0.7874 0.4064)
			(stroke
				(width 0.1524)
				(type default)
			)
			(layer "F.SilkS")
		)
		(fp_line
			(start -0.67945 -0.305054)
			(end -0.12065 -0.305054)
			(stroke
				(width 0.1)
				(type default)
			)
			(layer "F.Fab")
		)
		(fp_line
			(start -0.67945 0.3048)
			(end -0.67945 -0.305054)
			(stroke
				(width 0.1)
				(type default)
			)
			(layer "F.Fab")
		)
		(fp_line
			(start -0.12065 -0.305054)
			(end -0.12065 -0.2794)
			(stroke
				(width 0.1)
				(type default)
			)
			(layer "F.Fab")
		)
		(fp_line
			(start -0.12065 -0.2794)
			(end 0.12065 -0.2794)
			(stroke
				(width 0.1)
				(type default)
			)
			(layer "F.Fab")
		)
		(fp_line
			(start -0.12065 0.2794)
			(end -0.12065 0.3048)
			(stroke
				(width 0.1)
				(type default)
			)
			(layer "F.Fab")
		)
		(fp_line
			(start -0.12065 0.3048)
			(end -0.67945 0.3048)
			(stroke
				(width 0.1)
				(type default)
			)
			(layer "F.Fab")
		)
		(fp_line
			(start 0.120396 0.2794)
			(end -0.12065 0.2794)
			(stroke
				(width 0.1)
				(type default)
			)
			(layer "F.Fab")
		)
		(fp_line
			(start 0.120396 0.3048)
			(end 0.120396 0.2794)
			(stroke
				(width 0.1)
				(type default)
			)
			(layer "F.Fab")
		)
		(fp_line
			(start 0.12065 -0.3048)
			(end 0.67945 -0.3048)
			(stroke
				(width 0.1)
				(type default)
			)
			(layer "F.Fab")
		)
		(fp_line
			(start 0.12065 -0.2794)
			(end 0.12065 -0.3048)
			(stroke
				(width 0.1)
				(type default)
			)
			(layer "F.Fab")
		)
		(fp_line
			(start 0.67945 -0.3048)
			(end 0.67945 0.3048)
			(stroke
				(width 0.1)
				(type default)
			)
			(layer "F.Fab")
		)
		(fp_line
			(start 0.67945 0.3048)
			(end 0.120396 0.3048)
			(stroke
				(width 0.1)
				(type default)
			)
			(layer "F.Fab")
		)
		(pad "1" smd circle
			(at -0.40005 0)
			(size 0 0)
			(layers "F.Cu" "F.Mask" "F.Paste")
			(net "RST_SMB_SSD12_ISO_N")
		)
		(pad "2" smd circle
			(at 0.40005 0)
			(size 0 0)
			(layers "F.Cu" "F.Mask" "F.Paste")
			(net "GND")
		)
	)
	(footprint ""
		(layer "F.Cu")
		(at 264.909046 -26.03373)
		(property "Reference" "R4070"
			(at 0 0 0)
			(layer "F.SilkS")
			(hide yes)
			(effects
				(font
					(size 1.27 1.27)
				)
			)
		)
		(property "Value" ""
			(at 0 0 0)
			(layer "F.Fab")
			(effects
				(font
					(size 1.27 1.27)
				)
			)
		)
		(duplicate_pad_numbers_are_jumpers no)
		(fp_line
			(start -0.7874 -0.4064)
			(end 0.7874 -0.4064)
			(stroke
				(width 0.1524)
				(type default)
			)
			(layer "F.SilkS")
		)
		(fp_line
			(start -0.7874 0.4064)
			(end -0.7874 -0.4064)
			(stroke
				(width 0.1524)
				(type default)
			)
			(layer "F.SilkS")
		)
		(fp_line
			(start 0.7874 -0.4064)
			(end 0.7874 0.4064)
			(stroke
				(width 0.1524)
				(type default)
			)
			(layer "F.SilkS")
		)
		(fp_line
			(start 0.7874 0.4064)
			(end -0.7874 0.4064)
			(stroke
				(width 0.1524)
				(type default)
			)
			(layer "F.SilkS")
		)
		(fp_line
			(start -0.67945 -0.305054)
			(end -0.12065 -0.305054)
			(stroke
				(width 0.1)
				(type default)
			)
			(layer "F.Fab")
		)
		(fp_line
			(start -0.67945 0.3048)
			(end -0.67945 -0.305054)
			(stroke
				(width 0.1)
				(type default)
			)
			(layer "F.Fab")
		)
		(fp_line
			(start -0.12065 -0.305054)
			(end -0.12065 -0.2794)
			(stroke
				(width 0.1)
				(type default)
			)
			(layer "F.Fab")
		)
		(fp_line
			(start -0.12065 -0.2794)
			(end 0.12065 -0.2794)
			(stroke
				(width 0.1)
				(type default)
			)
			(layer "F.Fab")
		)
		(fp_line
			(start -0.12065 0.2794)
			(end -0.12065 0.3048)
			(stroke
				(width 0.1)
				(type default)
			)
			(layer "F.Fab")
		)
		(fp_line
			(start -0.12065 0.3048)
			(end -0.67945 0.3048)
			(stroke
				(width 0.1)
				(type default)
			)
			(layer "F.Fab")
		)
		(fp_line
			(start 0.120396 0.2794)
			(end -0.12065 0.2794)
			(stroke
				(width 0.1)
				(type default)
			)
			(layer "F.Fab")
		)
		(fp_line
			(start 0.120396 0.3048)
			(end 0.120396 0.2794)
			(stroke
				(width 0.1)
				(type default)
			)
			(layer "F.Fab")
		)
		(fp_line
			(start 0.12065 -0.3048)
			(end 0.67945 -0.3048)
			(stroke
				(width 0.1)
				(type default)
			)
			(layer "F.Fab")
		)
		(fp_line
			(start 0.12065 -0.2794)
			(end 0.12065 -0.3048)
			(stroke
				(width 0.1)
				(type default)
			)
			(layer "F.Fab")
		)
		(fp_line
			(start 0.67945 -0.3048)
			(end 0.67945 0.3048)
			(stroke
				(width 0.1)
				(type default)
			)
			(layer "F.Fab")
		)
		(fp_line
			(start 0.67945 0.3048)
			(end 0.120396 0.3048)
			(stroke
				(width 0.1)
				(type default)
			)
			(layer "F.Fab")
		)
		(pad "1" smd circle
			(at -0.40005 0)
			(size 0 0)
			(layers "F.Cu" "F.Mask" "F.Paste")
			(net "P3V3_AUX")
		)
		(pad "2" smd circle
			(at 0.40005 0)
			(size 0 0)
			(layers "F.Cu" "F.Mask" "F.Paste")
			(net "PRSNT_SSD9_R_N")
		)
	)
	(footprint ""
		(layer "F.Cu")
		(at 149.387814 -285.218632)
		(property "Reference" "C3232"
			(at 0 0 0)
			(layer "F.SilkS")
			(hide yes)
			(effects
				(font
					(size 1.27 1.27)
				)
			)
		)
		(property "Value" ""
			(at 0 0 0)
			(layer "F.Fab")
			(effects
				(font
					(size 1.27 1.27)
				)
			)
		)
		(duplicate_pad_numbers_are_jumpers no)
		(fp_line
			(start -1.2954 -0.5842)
			(end 1.2954 -0.5842)
			(stroke
				(width 0.1524)
				(type default)
			)
			(layer "F.SilkS")
		)
		(fp_line
			(start -1.2954 0.5842)
			(end -1.2954 -0.5842)
			(stroke
				(width 0.1524)
				(type default)
			)
			(layer "F.SilkS")
		)
		(fp_line
			(start 1.2954 -0.5842)
			(end 1.2954 0.5842)
			(stroke
				(width 0.1524)
				(type default)
			)
			(layer "F.SilkS")
		)
		(fp_line
			(start 1.2954 0.5842)
			(end -1.2954 0.5842)
			(stroke
				(width 0.1524)
				(type default)
			)
			(layer "F.SilkS")
		)
		(fp_line
			(start -1.1938 -0.4064)
			(end -0.8636 -0.4064)
			(stroke
				(width 0.1)
				(type default)
			)
			(layer "F.Fab")
		)
		(fp_line
			(start -1.1938 0.4064)
			(end -1.1938 -0.4064)
			(stroke
				(width 0.1)
				(type default)
			)
			(layer "F.Fab")
		)
		(fp_line
			(start -0.8636 -0.4572)
			(end 0.8636 -0.4572)
			(stroke
				(width 0.1)
				(type default)
			)
			(layer "F.Fab")
		)
		(fp_line
			(start -0.8636 -0.4064)
			(end -0.8636 -0.4572)
			(stroke
				(width 0.1)
				(type default)
			)
			(layer "F.Fab")
		)
		(fp_line
			(start -0.8636 0.4064)
			(end -1.1938 0.4064)
			(stroke
				(width 0.1)
				(type default)
			)
			(layer "F.Fab")
		)
		(fp_line
			(start -0.8636 0.4572)
			(end -0.8636 0.4064)
			(stroke
				(width 0.1)
				(type default)
			)
			(layer "F.Fab")
		)
		(fp_line
			(start 0.8636 -0.4572)
			(end 0.8636 -0.4064)
			(stroke
				(width 0.1)
				(type default)
			)
			(layer "F.Fab")
		)
		(fp_line
			(start 0.8636 -0.4064)
			(end 1.1938 -0.4064)
			(stroke
				(width 0.1)
				(type default)
			)
			(layer "F.Fab")
		)
		(fp_line
			(start 0.8636 0.4064)
			(end 0.8636 0.4572)
			(stroke
				(width 0.1)
				(type default)
			)
			(layer "F.Fab")
		)
		(fp_line
			(start 0.8636 0.4572)
			(end -0.8636 0.4572)
			(stroke
				(width 0.1)
				(type default)
			)
			(layer "F.Fab")
		)
		(fp_line
			(start 1.1938 -0.4064)
			(end 1.1938 0.4064)
			(stroke
				(width 0.1)
				(type default)
			)
			(layer "F.Fab")
		)
		(fp_line
			(start 1.1938 0.4064)
			(end 0.8636 0.4064)
			(stroke
				(width 0.1)
				(type default)
			)
			(layer "F.Fab")
		)
		(pad "1" smd rect
			(at -0.7366 0 270)
			(size 0.7112 0.8128)
			(layers "F.Cu" "F.Mask" "F.Paste")
			(net "PCEPLL7_VDDA18_PEX1")
		)
		(pad "2" smd rect
			(at 0.7366 0 270)
			(size 0.7112 0.8128)
			(layers "F.Cu" "F.Mask" "F.Paste")
			(net "GND")
		)
	)
	(footprint ""
		(layer "F.Cu")
		(at 121.04751 -36.686998 90)
		(property "Reference" "C3663"
			(at 0 0 90)
			(layer "F.SilkS")
			(hide yes)
			(effects
				(font
					(size 1.27 1.27)
				)
			)
		)
		(property "Value" ""
			(at 0 0 90)
			(layer "F.Fab")
			(effects
				(font
					(size 1.27 1.27)
				)
			)
		)
		(duplicate_pad_numbers_are_jumpers no)
		(fp_line
			(start 0.7874 -0.4064)
			(end 0.7874 0.4064)
			(stroke
				(width 0.1524)
				(type default)
			)
			(layer "F.SilkS")
		)
		(fp_line
			(start -0.7874 -0.4064)
			(end 0.7874 -0.4064)
			(stroke
				(width 0.1524)
				(type default)
			)
			(layer "F.SilkS")
		)
		(fp_line
			(start 0.7874 0.4064)
			(end -0.7874 0.4064)
			(stroke
				(width 0.1524)
				(type default)
			)
			(layer "F.SilkS")
		)
		(fp_line
			(start -0.7874 0.4064)
			(end -0.7874 -0.4064)
			(stroke
				(width 0.1524)
				(type default)
			)
			(layer "F.SilkS")
		)
		(fp_line
			(start -0.12065 -0.305054)
			(end -0.12065 -0.2794)
			(stroke
				(width 0.1)
				(type default)
			)
			(layer "F.Fab")
		)
		(fp_line
			(start -0.67945 -0.305054)
			(end -0.12065 -0.305054)
			(stroke
				(width 0.1)
				(type default)
			)
			(layer "F.Fab")
		)
		(fp_line
			(start 0.67945 -0.3048)
			(end 0.67945 0.3048)
			(stroke
				(width 0.1)
				(type default)
			)
			(layer "F.Fab")
		)
		(fp_line
			(start 0.12065 -0.3048)
			(end 0.67945 -0.3048)
			(stroke
				(width 0.1)
				(type default)
			)
			(layer "F.Fab")
		)
		(fp_line
			(start 0.12065 -0.2794)
			(end 0.12065 -0.3048)
			(stroke
				(width 0.1)
				(type default)
			)
			(layer "F.Fab")
		)
		(fp_line
			(start -0.12065 -0.2794)
			(end 0.12065 -0.2794)
			(stroke
				(width 0.1)
				(type default)
			)
			(layer "F.Fab")
		)
		(fp_line
			(start 0.120396 0.2794)
			(end -0.12065 0.2794)
			(stroke
				(width 0.1)
				(type default)
			)
			(layer "F.Fab")
		)
		(fp_line
			(start -0.12065 0.2794)
			(end -0.12065 0.3048)
			(stroke
				(width 0.1)
				(type default)
			)
			(layer "F.Fab")
		)
		(fp_line
			(start 0.67945 0.3048)
			(end 0.120396 0.3048)
			(stroke
				(width 0.1)
				(type default)
			)
			(layer "F.Fab")
		)
		(fp_line
			(start 0.120396 0.3048)
			(end 0.120396 0.2794)
			(stroke
				(width 0.1)
				(type default)
			)
			(layer "F.Fab")
		)
		(fp_line
			(start -0.12065 0.3048)
			(end -0.67945 0.3048)
			(stroke
				(width 0.1)
				(type default)
			)
			(layer "F.Fab")
		)
		(fp_line
			(start -0.67945 0.3048)
			(end -0.67945 -0.305054)
			(stroke
				(width 0.1)
				(type default)
			)
			(layer "F.Fab")
		)
		(pad "1" smd circle
			(at -0.40005 0 90)
			(size 0 0)
			(layers "F.Cu" "F.Mask" "F.Paste")
			(net "P3V3_AUX")
		)
		(pad "2" smd circle
			(at 0.40005 0 90)
			(size 0 0)
			(layers "F.Cu" "F.Mask" "F.Paste")
			(net "GND")
		)
	)
)
